# T6G (Grand Teton) — schematic netlist excerpt (pin names and nets, part order shuffled) for the footprints in the layout excerpt that follows; sources: Cadence DE-HDL packaged netlist, KiCad conversion of 04192023_DAF0TMB3IC0_F0TG_MB_C_brd_V02_OCP.brd

R2675  Q_RES  33.2 1% CHIP  pkg 0402LF  page 248 : A = I3C_BMC_SWB_BUF_R_SCL ; B = I3C_BMC_SWB_BUF_SCL
C6611  Q_CAP_DIFFBUS  DIFF BUS_0.22UF 6.3V 20% X6S  pkg C0201  page 308 : \1\ = P5E_CPU0_P3_TX_BUF_C_DP<7> ; \2\ = P5E_CPU0_P3_TX_BUF_DP<7>
C2646  Q_CAP  22UF 4V 20% X6S  pkg C0402  page 70 : A = PVDD11_S3_P0 ; B = GND

(kicad_pcb
	(version 20260206)
	(generator "pcbnew")
	(generator_version "10.0")
	(general
		(thickness 1.6)
		(legacy_teardrops no)
	)
	(paper "A4")
	(title_block
		(title "04192023_DAF0TMB3IC0_F0TG_MB_C_brd_V02_OCP.brd")
		(comment 1 "Grand Teton / footprints 6749-6751 of 8354")
	)
	(layers
		(0 "F.Cu" signal "TOP")
		(4 "In1.Cu" signal "GND")
		(6 "In2.Cu" signal "IN1")
		(8 "In3.Cu" signal "GND1")
		(10 "In4.Cu" signal "IN2")
		(12 "In5.Cu" signal "GND2")
		(14 "In6.Cu" signal "IN3")
		(16 "In7.Cu" signal "GND3")
		(18 "In8.Cu" signal "VCC")
		(20 "In9.Cu" signal "VCC1")
		(22 "In10.Cu" signal "GND4")
		(24 "In11.Cu" signal "IN4")
		(26 "In12.Cu" signal "GND5")
		(28 "In13.Cu" signal "IN5")
		(30 "In14.Cu" signal "GND6")
		(32 "In15.Cu" signal "IN6")
		(34 "In16.Cu" signal "GND7")
		(2 "B.Cu" signal "BOTTOM")
		(9 "F.Adhes" user "F.Adhesive")
		(11 "B.Adhes" user "B.Adhesive")
		(13 "F.Paste" user "Package Geometry/Pastemask Top")
		(15 "B.Paste" user "Package Geometry/Pastemask Bottom")
		(5 "F.SilkS" user "Ref Des/Silkscreen Top")
		(7 "B.SilkS" user "Ref Des/Silkscreen Bottom")
		(1 "F.Mask" user "Board Geometry/Soldermask Top")
		(3 "B.Mask" user "Board Geometry/Soldermask Bottom")
		(17 "Dwgs.User" user "User.Drawings")
		(19 "Cmts.User" user "User.Comments")
		(21 "Eco1.User" user "User.Eco1")
		(23 "Eco2.User" user "User.Eco2")
		(25 "Edge.Cuts" user "Board Geometry/Outline")
		(27 "Margin" user)
		(31 "F.CrtYd" user "Package Geometry/Place Bound Top")
		(29 "B.CrtYd" user "Package Geometry/Place Bound Bottom")
		(35 "F.Fab" user "Ref Des/Assembly Top")
		(33 "B.Fab" user "Ref Des/Assembly Bottom")
	)
	(footprint ""
		(layer "B.Cu")
		(at 288.29 -426.466 180)
		(property "Reference" "R2675"
			(at 0 0 0)
			(layer "B.SilkS")
			(hide yes)
			(effects
				(font
					(size 1.27 1.27)
				)
				(justify mirror)
			)
		)
		(property "Value" ""
			(at 0 0 0)
			(layer "B.Fab")
			(effects
				(font
					(size 1.27 1.27)
				)
				(justify mirror)
			)
		)
		(duplicate_pad_numbers_are_jumpers no)
		(fp_line
			(start 0.7874 0.4064)
			(end 0.7874 -0.4064)
			(stroke
				(width 0.1524)
				(type default)
			)
			(layer "B.SilkS")
		)
		(fp_line
			(start 0.7874 -0.4064)
			(end -0.7874 -0.4064)
			(stroke
				(width 0.1524)
				(type default)
			)
			(layer "B.SilkS")
		)
		(fp_line
			(start -0.7874 0.4064)
			(end 0.7874 0.4064)
			(stroke
				(width 0.1524)
				(type default)
			)
			(layer "B.SilkS")
		)
		(fp_line
			(start -0.7874 -0.4064)
			(end -0.7874 0.4064)
			(stroke
				(width 0.1524)
				(type default)
			)
			(layer "B.SilkS")
		)
		(fp_line
			(start 0.67945 0.3048)
			(end 0.67945 -0.305054)
			(stroke
				(width 0.1)
				(type default)
			)
			(layer "B.Fab")
		)
		(fp_line
			(start 0.67945 -0.305054)
			(end 0.12065 -0.305054)
			(stroke
				(width 0.1)
				(type default)
			)
			(layer "B.Fab")
		)
		(fp_line
			(start 0.12065 0.3048)
			(end 0.67945 0.3048)
			(stroke
				(width 0.1)
				(type default)
			)
			(layer "B.Fab")
		)
		(fp_line
			(start 0.12065 0.2794)
			(end 0.12065 0.3048)
			(stroke
				(width 0.1)
				(type default)
			)
			(layer "B.Fab")
		)
		(fp_line
			(start 0.12065 -0.2794)
			(end -0.12065 -0.2794)
			(stroke
				(width 0.1)
				(type default)
			)
			(layer "B.Fab")
		)
		(fp_line
			(start 0.12065 -0.305054)
			(end 0.12065 -0.2794)
			(stroke
				(width 0.1)
				(type default)
			)
			(layer "B.Fab")
		)
		(fp_line
			(start -0.120396 0.3048)
			(end -0.120396 0.2794)
			(stroke
				(width 0.1)
				(type default)
			)
			(layer "B.Fab")
		)
		(fp_line
			(start -0.120396 0.2794)
			(end 0.12065 0.2794)
			(stroke
				(width 0.1)
				(type default)
			)
			(layer "B.Fab")
		)
		(fp_line
			(start -0.12065 -0.2794)
			(end -0.12065 -0.3048)
			(stroke
				(width 0.1)
				(type default)
			)
			(layer "B.Fab")
		)
		(fp_line
			(start -0.12065 -0.3048)
			(end -0.67945 -0.3048)
			(stroke
				(width 0.1)
				(type default)
			)
			(layer "B.Fab")
		)
		(fp_line
			(start -0.67945 0.3048)
			(end -0.120396 0.3048)
			(stroke
				(width 0.1)
				(type default)
			)
			(layer "B.Fab")
		)
		(fp_line
			(start -0.67945 -0.3048)
			(end -0.67945 0.3048)
			(stroke
				(width 0.1)
				(type default)
			)
			(layer "B.Fab")
		)
		(pad "1" smd circle
			(at 0.40005 0)
			(size 0 0)
			(layers "B.Cu" "B.Mask" "B.Paste")
			(net "I3C_BMC_SWB_BUF_R_SCL")
		)
		(pad "2" smd circle
			(at -0.40005 0)
			(size 0 0)
			(layers "B.Cu" "B.Mask" "B.Paste")
			(net "I3C_BMC_SWB_BUF_SCL")
		)
	)
	(footprint ""
		(layer "B.Cu")
		(at 394.757402 -416.899344 90)
		(property "Reference" "C6611"
			(at 0 0 90)
			(layer "B.SilkS")
			(hide yes)
			(effects
				(font
					(size 1.27 1.27)
				)
				(justify mirror)
			)
		)
		(property "Value" ""
			(at 0 0 90)
			(layer "B.Fab")
			(effects
				(font
					(size 1.27 1.27)
				)
				(justify mirror)
			)
		)
		(duplicate_pad_numbers_are_jumpers no)
		(fp_line
			(start 0.299974 -0.150114)
			(end -0.299974 -0.150114)
			(stroke
				(width 0.1)
				(type default)
			)
			(layer "B.Fab")
		)
		(fp_line
			(start -0.299974 -0.150114)
			(end -0.299974 0.150114)
			(stroke
				(width 0.1)
				(type default)
			)
			(layer "B.Fab")
		)
		(fp_line
			(start 0.299974 0.150114)
			(end 0.299974 -0.150114)
			(stroke
				(width 0.1)
				(type default)
			)
			(layer "B.Fab")
		)
		(fp_line
			(start -0.299974 0.150114)
			(end 0.299974 0.150114)
			(stroke
				(width 0.1)
				(type default)
			)
			(layer "B.Fab")
		)
		(pad "1" smd rect
			(at 0.2667 0 270)
			(size 0.3048 0.381)
			(layers "B.Cu" "B.Mask" "B.Paste")
			(net "P5E_CPU0_P3_TX_BUF_C_DP<7>")
		)
		(pad "2" smd rect
			(at -0.2667 0 270)
			(size 0.3048 0.381)
			(layers "B.Cu" "B.Mask" "B.Paste")
			(net "P5E_CPU0_P3_TX_BUF_DP<7>")
		)
	)
	(footprint ""
		(layer "B.Cu")
		(at 361.899454 -266.00531)
		(property "Reference" "C2646"
			(at 0 0 0)
			(layer "B.SilkS")
			(hide yes)
			(effects
				(font
					(size 1.27 1.27)
				)
				(justify mirror)
			)
		)
		(property "Value" ""
			(at 0 0 0)
			(layer "B.Fab")
			(effects
				(font
					(size 1.27 1.27)
				)
				(justify mirror)
			)
		)
		(duplicate_pad_numbers_are_jumpers no)
		(fp_line
			(start -0.7874 -0.4064)
			(end -0.7874 0.4064)
			(stroke
				(width 0.1524)
				(type default)
			)
			(layer "B.SilkS")
		)
		(fp_line
			(start -0.7874 0.4064)
			(end 0.7874 0.4064)
			(stroke
				(width 0.1524)
				(type default)
			)
			(layer "B.SilkS")
		)
		(fp_line
			(start 0.7874 -0.4064)
			(end -0.7874 -0.4064)
			(stroke
				(width 0.1524)
				(type default)
			)
			(layer "B.SilkS")
		)
		(fp_line
			(start 0.7874 0.4064)
			(end 0.7874 -0.4064)
			(stroke
				(width 0.1524)
				(type default)
			)
			(layer "B.SilkS")
		)
		(fp_line
			(start -0.67945 -0.3048)
			(end -0.67945 0.3048)
			(stroke
				(width 0.1)
				(type default)
			)
			(layer "B.Fab")
		)
		(fp_line
			(start -0.67945 0.3048)
			(end -0.120396 0.3048)
			(stroke
				(width 0.1)
				(type default)
			)
			(layer "B.Fab")
		)
		(fp_line
			(start -0.12065 -0.3048)
			(end -0.67945 -0.3048)
			(stroke
				(width 0.1)
				(type default)
			)
			(layer "B.Fab")
		)
		(fp_line
			(start -0.12065 -0.2794)
			(end -0.12065 -0.3048)
			(stroke
				(width 0.1)
				(type default)
			)
			(layer "B.Fab")
		)
		(fp_line
			(start -0.120396 0.2794)
			(end 0.12065 0.2794)
			(stroke
				(width 0.1)
				(type default)
			)
			(layer "B.Fab")
		)
		(fp_line
			(start -0.120396 0.3048)
			(end -0.120396 0.2794)
			(stroke
				(width 0.1)
				(type default)
			)
			(layer "B.Fab")
		)
		(fp_line
			(start 0.12065 -0.305054)
			(end 0.12065 -0.2794)
			(stroke
				(width 0.1)
				(type default)
			)
			(layer "B.Fab")
		)
		(fp_line
			(start 0.12065 -0.2794)
			(end -0.12065 -0.2794)
			(stroke
				(width 0.1)
				(type default)
			)
			(layer "B.Fab")
		)
		(fp_line
			(start 0.12065 0.2794)
			(end 0.12065 0.3048)
			(stroke
				(width 0.1)
				(type default)
			)
			(layer "B.Fab")
		)
		(fp_line
			(start 0.12065 0.3048)
			(end 0.67945 0.3048)
			(stroke
				(width 0.1)
				(type default)
			)
			(layer "B.Fab")
		)
		(fp_line
			(start 0.67945 -0.305054)
			(end 0.12065 -0.305054)
			(stroke
				(width 0.1)
				(type default)
			)
			(layer "B.Fab")
		)
		(fp_line
			(start 0.67945 0.3048)
			(end 0.67945 -0.305054)
			(stroke
				(width 0.1)
				(type default)
			)
			(layer "B.Fab")
		)
		(pad "1" smd circle
			(at 0.40005 0 180)
			(size 0 0)
			(layers "B.Cu" "B.Mask" "B.Paste")
			(net "PVDD11_S3_P0")
		)
		(pad "2" smd circle
			(at -0.40005 0 180)
			(size 0 0)
			(layers "B.Cu" "B.Mask" "B.Paste")
			(net "GND")
		)
	)
)
